# S9S_MB_2U (Grand Teton) — schematic netlist excerpt (pin names and nets, part order shuffled) for the footprints in the layout excerpt that follows; sources: Cadence DE-HDL packaged netlist, KiCad conversion of 03242023_DA0F0TMBIJ0_F0T_Motherboard_J_brd_V01_OCP.brd

PR4254  Q_RES  0 5% CHIP  pkg 0402LF  page 296 : A = NC_PVCCD_HV_CPU1_ACSP5 ; B = GND
R3570  Q_RES  10 1% CHIP  pkg 0402LF  page 172 : A = P3V3_OCP_V3_2_R ; B = VSENSE_P12V_INA230_3_INP

(kicad_pcb
	(version 20260206)
	(generator "pcbnew")
	(generator_version "10.0")
	(general
		(thickness 1.6)
		(legacy_teardrops no)
	)
	(paper "A4")
	(title_block
		(title "03242023_DA0F0TMBIJ0_F0T_Motherboard_J_brd_V01_OCP.brd")
		(comment 1 "Grand Teton / footprints 4233-4234 of 6105")
	)
	(layers
		(0 "F.Cu" signal "TOP")
		(4 "In1.Cu" signal "GND")
		(6 "In2.Cu" signal "IN1")
		(8 "In3.Cu" signal "GND1")
		(10 "In4.Cu" signal "IN2")
		(12 "In5.Cu" signal "GND2")
		(14 "In6.Cu" signal "IN3")
		(16 "In7.Cu" signal "GND3")
		(18 "In8.Cu" signal "VCC")
		(20 "In9.Cu" signal "VCC1")
		(22 "In10.Cu" signal "GND4")
		(24 "In11.Cu" signal "IN4")
		(26 "In12.Cu" signal "GND5")
		(28 "In13.Cu" signal "IN5")
		(30 "In14.Cu" signal "GND6")
		(32 "In15.Cu" signal "IN6")
		(34 "In16.Cu" signal "GND7")
		(2 "B.Cu" signal "BOTTOM")
		(9 "F.Adhes" user "F.Adhesive")
		(11 "B.Adhes" user "B.Adhesive")
		(13 "F.Paste" user "Package Geometry/Pastemask Top")
		(15 "B.Paste" user "Package Geometry/Pastemask Bottom")
		(5 "F.SilkS" user "Ref Des/Silkscreen Top")
		(7 "B.SilkS" user "Ref Des/Silkscreen Bottom")
		(1 "F.Mask" user "Board Geometry/Soldermask Top")
		(3 "B.Mask" user "Board Geometry/Soldermask Bottom")
		(17 "Dwgs.User" user "User.Drawings")
		(19 "Cmts.User" user "User.Comments")
		(21 "Eco1.User" user "User.Eco1")
		(23 "Eco2.User" user "User.Eco2")
		(25 "Edge.Cuts" user "Board Geometry/Outline")
		(27 "Margin" user)
		(31 "F.CrtYd" user "Package Geometry/Place Bound Top")
		(29 "B.CrtYd" user "Package Geometry/Place Bound Bottom")
		(35 "F.Fab" user "Ref Des/Assembly Top")
		(33 "B.Fab" user "Ref Des/Assembly Bottom")
	)
	(footprint ""
		(layer "B.Cu")
		(at 26.7716 -162.829748 -90)
		(property "Reference" "PR4254"
			(at 0 0 90)
			(layer "B.SilkS")
			(hide yes)
			(effects
				(font
					(size 1.27 1.27)
				)
				(justify mirror)
			)
		)
		(property "Value" ""
			(at 0 0 90)
			(layer "B.Fab")
			(effects
				(font
					(size 1.27 1.27)
				)
				(justify mirror)
			)
		)
		(duplicate_pad_numbers_are_jumpers no)
		(fp_line
			(start -0.7874 0.4064)
			(end 0.7874 0.4064)
			(stroke
				(width 0.1524)
				(type default)
			)
			(layer "B.SilkS")
		)
		(fp_line
			(start 0.7874 0.4064)
			(end 0.7874 -0.4064)
			(stroke
				(width 0.1524)
				(type default)
			)
			(layer "B.SilkS")
		)
		(fp_line
			(start -0.7874 -0.4064)
			(end -0.7874 0.4064)
			(stroke
				(width 0.1524)
				(type default)
			)
			(layer "B.SilkS")
		)
		(fp_line
			(start 0.7874 -0.4064)
			(end -0.7874 -0.4064)
			(stroke
				(width 0.1524)
				(type default)
			)
			(layer "B.SilkS")
		)
		(fp_line
			(start -0.67945 0.3048)
			(end -0.120396 0.3048)
			(stroke
				(width 0.1)
				(type default)
			)
			(layer "B.Fab")
		)
		(fp_line
			(start -0.120396 0.3048)
			(end -0.120396 0.2794)
			(stroke
				(width 0.1)
				(type default)
			)
			(layer "B.Fab")
		)
		(fp_line
			(start 0.12065 0.3048)
			(end 0.67945 0.3048)
			(stroke
				(width 0.1)
				(type default)
			)
			(layer "B.Fab")
		)
		(fp_line
			(start 0.67945 0.3048)
			(end 0.67945 -0.305054)
			(stroke
				(width 0.1)
				(type default)
			)
			(layer "B.Fab")
		)
		(fp_line
			(start -0.120396 0.2794)
			(end 0.12065 0.2794)
			(stroke
				(width 0.1)
				(type default)
			)
			(layer "B.Fab")
		)
		(fp_line
			(start 0.12065 0.2794)
			(end 0.12065 0.3048)
			(stroke
				(width 0.1)
				(type default)
			)
			(layer "B.Fab")
		)
		(fp_line
			(start -0.12065 -0.2794)
			(end -0.12065 -0.3048)
			(stroke
				(width 0.1)
				(type default)
			)
			(layer "B.Fab")
		)
		(fp_line
			(start 0.12065 -0.2794)
			(end -0.12065 -0.2794)
			(stroke
				(width 0.1)
				(type default)
			)
			(layer "B.Fab")
		)
		(fp_line
			(start -0.67945 -0.3048)
			(end -0.67945 0.3048)
			(stroke
				(width 0.1)
				(type default)
			)
			(layer "B.Fab")
		)
		(fp_line
			(start -0.12065 -0.3048)
			(end -0.67945 -0.3048)
			(stroke
				(width 0.1)
				(type default)
			)
			(layer "B.Fab")
		)
		(fp_line
			(start 0.12065 -0.305054)
			(end 0.12065 -0.2794)
			(stroke
				(width 0.1)
				(type default)
			)
			(layer "B.Fab")
		)
		(fp_line
			(start 0.67945 -0.305054)
			(end 0.12065 -0.305054)
			(stroke
				(width 0.1)
				(type default)
			)
			(layer "B.Fab")
		)
		(pad "1" smd circle
			(at 0.40005 0 90)
			(size 0 0)
			(layers "B.Cu" "B.Mask" "B.Paste")
			(net "NC_PVCCD_HV_CPU1_ACSP5")
		)
		(pad "2" smd circle
			(at -0.40005 0 90)
			(size 0 0)
			(layers "B.Cu" "B.Mask" "B.Paste")
			(net "GND")
		)
	)
	(footprint ""
		(layer "B.Cu")
		(at 77.142594 -46.044866)
		(property "Reference" "R3570"
			(at 0 0 0)
			(layer "B.SilkS")
			(hide yes)
			(effects
				(font
					(size 1.27 1.27)
				)
				(justify mirror)
			)
		)
		(property "Value" ""
			(at 0 0 0)
			(layer "B.Fab")
			(effects
				(font
					(size 1.27 1.27)
				)
				(justify mirror)
			)
		)
		(duplicate_pad_numbers_are_jumpers no)
		(fp_line
			(start -0.7874 -0.4064)
			(end -0.7874 0.4064)
			(stroke
				(width 0.1524)
				(type default)
			)
			(layer "B.SilkS")
		)
		(fp_line
			(start -0.7874 0.4064)
			(end 0.7874 0.4064)
			(stroke
				(width 0.1524)
				(type default)
			)
			(layer "B.SilkS")
		)
		(fp_line
			(start 0.7874 -0.4064)
			(end -0.7874 -0.4064)
			(stroke
				(width 0.1524)
				(type default)
			)
			(layer "B.SilkS")
		)
		(fp_line
			(start 0.7874 0.4064)
			(end 0.7874 -0.4064)
			(stroke
				(width 0.1524)
				(type default)
			)
			(layer "B.SilkS")
		)
		(fp_line
			(start -0.67945 -0.3048)
			(end -0.67945 0.3048)
			(stroke
				(width 0.1)
				(type default)
			)
			(layer "B.Fab")
		)
		(fp_line
			(start -0.67945 0.3048)
			(end -0.120396 0.3048)
			(stroke
				(width 0.1)
				(type default)
			)
			(layer "B.Fab")
		)
		(fp_line
			(start -0.12065 -0.3048)
			(end -0.67945 -0.3048)
			(stroke
				(width 0.1)
				(type default)
			)
			(layer "B.Fab")
		)
		(fp_line
			(start -0.12065 -0.2794)
			(end -0.12065 -0.3048)
			(stroke
				(width 0.1)
				(type default)
			)
			(layer "B.Fab")
		)
		(fp_line
			(start -0.120396 0.2794)
			(end 0.12065 0.2794)
			(stroke
				(width 0.1)
				(type default)
			)
			(layer "B.Fab")
		)
		(fp_line
			(start -0.120396 0.3048)
			(end -0.120396 0.2794)
			(stroke
				(width 0.1)
				(type default)
			)
			(layer "B.Fab")
		)
		(fp_line
			(start 0.12065 -0.305054)
			(end 0.12065 -0.2794)
			(stroke
				(width 0.1)
				(type default)
			)
			(layer "B.Fab")
		)
		(fp_line
			(start 0.12065 -0.2794)
			(end -0.12065 -0.2794)
			(stroke
				(width 0.1)
				(type default)
			)
			(layer "B.Fab")
		)
		(fp_line
			(start 0.12065 0.2794)
			(end 0.12065 0.3048)
			(stroke
				(width 0.1)
				(type default)
			)
			(layer "B.Fab")
		)
		(fp_line
			(start 0.12065 0.3048)
			(end 0.67945 0.3048)
			(stroke
				(width 0.1)
				(type default)
			)
			(layer "B.Fab")
		)
		(fp_line
			(start 0.67945 -0.305054)
			(end 0.12065 -0.305054)
			(stroke
				(width 0.1)
				(type default)
			)
			(layer "B.Fab")
		)
		(fp_line
			(start 0.67945 0.3048)
			(end 0.67945 -0.305054)
			(stroke
				(width 0.1)
				(type default)
			)
			(layer "B.Fab")
		)
		(pad "1" smd circle
			(at 0.40005 0 180)
			(size 0 0)
			(layers "B.Cu" "B.Mask" "B.Paste")
			(net "P3V3_OCP_V3_2_R")
		)
		(pad "2" smd circle
			(at -0.40005 0 180)
			(size 0 0)
			(layers "B.Cu" "B.Mask" "B.Paste")
			(net "VSENSE_P12V_INA230_3_INP")
		)
	)
)
